(kicad_pcb
	(version 20260206)
	(generator "pcbnew")
	(generator_version "10.0")
	(general
		(thickness 1.6)
		(legacy_teardrops no)
	)
	(paper "A4")
	(title_block
		(title "v1-tray-backplane — T6M_tray_BP_c_1023_1120.brd")
		(comment 1 "Open CloudServer (Microsoft) / footprints 35-37 of 170")
	)
	(layers
		(0 "F.Cu" signal "TOP")
		(4 "In1.Cu" signal "GND")
		(6 "In2.Cu" signal "IN1")
		(8 "In3.Cu" signal "VCC")
		(10 "In4.Cu" signal "VCC1")
		(12 "In5.Cu" signal "IN2")
		(14 "In6.Cu" signal "GND1")
		(2 "B.Cu" signal "BOTTOM")
		(9 "F.Adhes" user "F.Adhesive")
		(11 "B.Adhes" user "B.Adhesive")
		(13 "F.Paste" user "Package Geometry/Pastemask Top")
		(15 "B.Paste" user "Package Geometry/Pastemask Bottom")
		(5 "F.SilkS" user "Ref Des/Silkscreen Top")
		(7 "B.SilkS" user "Ref Des/Silkscreen Bottom")
		(1 "F.Mask" user "Board Geometry/Soldermask Top")
		(3 "B.Mask" user "Board Geometry/Soldermask Bottom")
		(17 "Dwgs.User" user "User.Drawings")
		(19 "Cmts.User" user "User.Comments")
		(21 "Eco1.User" user "User.Eco1")
		(23 "Eco2.User" user "User.Eco2")
		(25 "Edge.Cuts" user "Board Geometry/Outline")
		(27 "Margin" user)
		(31 "F.CrtYd" user "Package Geometry/Place Bound Top")
		(29 "B.CrtYd" user "Package Geometry/Place Bound Bottom")
		(35 "F.Fab" user "Ref Des/Assembly Top")
		(33 "B.Fab" user "Ref Des/Assembly Bottom")
	)
	(footprint ""
		(layer "F.Cu")
		(at 155.459938 -10.6299)
		(property "Reference" "J12"
			(at -0.7112 -11.064748 0)
			(unlocked yes)
			(layer "F.SilkS")
			(effects
				(font
					(size 0.7874 0.5842)
					(thickness 0.1524)
				)
				(justify left)
			)
		)
		(property "Value" ""
			(at 0 0 0)
			(layer "F.Fab")
			(effects
				(font
					(size 1.27 1.27)
				)
			)
		)
		(duplicate_pad_numbers_are_jumpers no)
		(fp_line
			(start -5.32511 -10.500106)
			(end -5.32511 0)
			(stroke
				(width 0.1524)
				(type default)
			)
			(layer "F.SilkS")
		)
		(fp_line
			(start -5.32511 0)
			(end -5.32511 43.029886)
			(stroke
				(width 0.1524)
				(type default)
			)
			(layer "F.SilkS")
		)
		(fp_line
			(start -5.32511 13.129768)
			(end 5.32511 13.129768)
			(stroke
				(width 0.1524)
				(type default)
			)
			(layer "F.SilkS")
		)
		(fp_line
			(start -5.32511 43.029886)
			(end 5.32511 43.029886)
			(stroke
				(width 0.1524)
				(type default)
			)
			(layer "F.SilkS")
		)
		(fp_line
			(start 5.32511 -10.500106)
			(end -5.32511 -10.500106)
			(stroke
				(width 0.1524)
				(type default)
			)
			(layer "F.SilkS")
		)
		(fp_line
			(start 5.32511 43.029886)
			(end 5.32511 -10.500106)
			(stroke
				(width 0.1524)
				(type default)
			)
			(layer "F.SilkS")
		)
		(fp_poly
			(pts
				(xy -7.865364 4.480814) (xy -6.59003 5.755894) (xy -6.581902 5.764276) (xy -6.015228 3.852164)
			)
			(stroke
				(width 0)
				(type default)
			)
			(fill yes)
			(layer "F.SilkS")
		)
		(fp_poly
			(pts
				(arc
					(start 2.758694 0)
					(mid -2.758694 0)
					(end 2.758694 0)
				)
			)
			(stroke
				(width 0)
				(type default)
			)
			(fill no)
			(layer "B.CrtYd")
		)
		(fp_poly
			(pts
				(arc
					(start 2.758694 5.62991)
					(mid -2.758694 5.62991)
					(end 2.758694 5.62991)
				)
			)
			(stroke
				(width 0)
				(type default)
			)
			(fill no)
			(layer "B.CrtYd")
		)
		(fp_poly
			(pts
				(arc
					(start 2.95275 -6.620002)
					(mid -2.95275 -6.620002)
					(end 2.95275 -6.620002)
				)
			)
			(stroke
				(width 0)
				(type default)
			)
			(fill no)
			(layer "B.CrtYd")
		)
		(fp_poly
			(pts
				(xy -5.32511 0) (xy -5.32511 43.029886) (xy 5.32511 43.029886) (xy 5.32511 -10.500106) (xy -5.32511 -10.500106)
			)
			(stroke
				(width 0)
				(type default)
			)
			(fill no)
			(layer "F.CrtYd")
		)
		(fp_line
			(start -5.32511 -10.500106)
			(end -5.32511 0)
			(stroke
				(width 0.1)
				(type default)
			)
			(layer "F.Fab")
		)
		(fp_line
			(start -5.32511 0)
			(end -5.32511 43.029886)
			(stroke
				(width 0.1)
				(type default)
			)
			(layer "F.Fab")
		)
		(fp_line
			(start -5.32511 13.129768)
			(end 5.32511 13.129768)
			(stroke
				(width 0.1)
				(type default)
			)
			(layer "F.Fab")
		)
		(fp_line
			(start -5.32511 43.029886)
			(end 5.32511 43.029886)
			(stroke
				(width 0.1)
				(type default)
			)
			(layer "F.Fab")
		)
		(fp_line
			(start 5.32511 -10.500106)
			(end -5.32511 -10.500106)
			(stroke
				(width 0.1)
				(type default)
			)
			(layer "F.Fab")
		)
		(fp_line
			(start 5.32511 43.029886)
			(end 5.32511 -10.500106)
			(stroke
				(width 0.1)
				(type default)
			)
			(layer "F.Fab")
		)
		(fp_poly
			(pts
				(xy -7.86638 -0.8636) (xy -7.86638 0.9398) (xy -7.86638 0.951484) (xy -6.11378 0)
			)
			(stroke
				(width 0)
				(type default)
			)
			(fill yes)
			(layer "F.Fab")
		)
		(fp_text user "1"
			(at -6.082284 3.770884 0)
			(unlocked yes)
			(layer "F.SilkS")
			(effects
				(font
					(size 0.7874 0.5842)
					(thickness 0.1524)
				)
				(justify left)
			)
		)
		(fp_text user "1"
			(at -2.9464 0.043688 0)
			(unlocked yes)
			(layer "B.SilkS")
			(effects
				(font
					(size 0.7874 0.5842)
					(thickness 0.1524)
				)
				(justify left mirror)
			)
		)
		(fp_text user "1"
			(at -2.9464 0.043688 0)
			(unlocked yes)
			(layer "B.Fab")
			(effects
				(font
					(size 0.7874 0.5842)
					(thickness 0.000001)
				)
				(justify left mirror)
			)
		)
		(fp_text user "1"
			(at -6.031484 -0.039116 0)
			(unlocked yes)
			(layer "F.Fab")
			(effects
				(font
					(size 0.7874 0.5842)
					(thickness 0.000001)
				)
				(justify left)
			)
		)
		(pad "1" thru_hole circle
			(at 0 0)
			(size 5.4102 5.4102)
			(drill 4.0132)
			(layers "*.Cu" "*.Mask")
			(remove_unused_layers no)
			(net "GND")
			(clearance -0.4445)
		)
		(pad "2" thru_hole circle
			(at 0 5.62991)
			(size 5.4102 5.4102)
			(drill 4.0132)
			(layers "*.Cu" "*.Mask")
			(remove_unused_layers no)
			(net "GND")
			(clearance -0.4445)
		)
		(pad "3" thru_hole circle
			(at 0 -6.620002)
			(size 5.7912 5.7912)
			(drill 4.0132)
			(layers "*.Cu" "*.Mask")
			(remove_unused_layers no)
			(net "GND")
			(clearance -0.635)
		)
	)
	(footprint ""
		(layer "F.Cu")
		(at 29.707332 -19.7358 -90)
		(property "Reference" "R88"
			(at 0.9144 -4.907788 90)
			(unlocked yes)
			(layer "F.SilkS")
			(effects
				(font
					(size 0.7874 0.5842)
					(thickness 0.1524)
				)
				(justify left)
			)
		)
		(property "Value" ""
			(at 0 0 270)
			(layer "F.Fab")
			(effects
				(font
					(size 1.27 1.27)
				)
			)
		)
		(duplicate_pad_numbers_are_jumpers no)
		(fp_line
			(start -0.7874 0.4064)
			(end -0.7874 -0.4064)
			(stroke
				(width 0.1524)
				(type default)
			)
			(layer "F.SilkS")
		)
		(fp_line
			(start 0.7874 0.4064)
			(end -0.7874 0.4064)
			(stroke
				(width 0.1524)
				(type default)
			)
			(layer "F.SilkS")
		)
		(fp_line
			(start -0.7874 -0.4064)
			(end 0.7874 -0.4064)
			(stroke
				(width 0.1524)
				(type default)
			)
			(layer "F.SilkS")
		)
		(fp_line
			(start 0.7874 -0.4064)
			(end 0.7874 0.4064)
			(stroke
				(width 0.1524)
				(type default)
			)
			(layer "F.SilkS")
		)
		(fp_poly
			(pts
				(xy -0.508 0.2794) (xy -0.508 0.2286) (xy -0.635 0.2286) (xy -0.635 -0.254) (xy -0.5334 -0.254)
				(xy -0.5334 -0.2794) (xy 0.5334 -0.2794) (xy 0.5334 -0.254) (xy 0.635 -0.254) (xy 0.635 0.254) (xy 0.5334 0.254)
				(xy 0.5334 0.2794)
			)
			(stroke
				(width 0)
				(type default)
			)
			(fill no)
			(layer "F.CrtYd")
		)
		(pad "1" smd rect
			(at 0.40005 0 270)
			(size 0.4572 0.508)
			(layers "F.Cu" "F.Mask" "F.Paste")
			(net "N39395053")
		)
		(pad "2" smd rect
			(at -0.40005 0 270)
			(size 0.4572 0.508)
			(layers "F.Cu" "F.Mask" "F.Paste")
			(net "P12V")
		)
	)
	(footprint ""
		(layer "F.Cu")
		(at 119.433848 -21.147532 180)
		(property "Reference" "R69"
			(at 60.737496 -5.119116 0)
			(unlocked yes)
			(layer "F.SilkS")
			(effects
				(font
					(size 0.7874 0.5842)
					(thickness 0.1524)
				)
				(justify left)
			)
		)
		(property "Value" ""
			(at 0 0 180)
			(layer "F.Fab")
			(effects
				(font
					(size 1.27 1.27)
				)
			)
		)
		(duplicate_pad_numbers_are_jumpers no)
		(fp_line
			(start 0.7874 0.4064)
			(end -0.7874 0.4064)
			(stroke
				(width 0.1524)
				(type default)
			)
			(layer "F.SilkS")
		)
		(fp_line
			(start 0.7874 -0.4064)
			(end 0.7874 0.4064)
			(stroke
				(width 0.1524)
				(type default)
			)
			(layer "F.SilkS")
		)
		(fp_line
			(start -0.7874 0.4064)
			(end -0.7874 -0.4064)
			(stroke
				(width 0.1524)
				(type default)
			)
			(layer "F.SilkS")
		)
		(fp_line
			(start -0.7874 -0.4064)
			(end 0.7874 -0.4064)
			(stroke
				(width 0.1524)
				(type default)
			)
			(layer "F.SilkS")
		)
		(fp_poly
			(pts
				(xy -0.508 0.2794) (xy -0.508 0.2286) (xy -0.635 0.2286) (xy -0.635 -0.254) (xy -0.5334 -0.254)
				(xy -0.5334 -0.2794) (xy 0.5334 -0.2794) (xy 0.5334 -0.254) (xy 0.635 -0.254) (xy 0.635 0.254) (xy 0.5334 0.254)
				(xy 0.5334 0.2794)
			)
			(stroke
				(width 0)
				(type default)
			)
			(fill no)
			(layer "F.CrtYd")
		)
		(pad "1" smd rect
			(at 0.40005 0 180)
			(size 0.4572 0.508)
			(layers "F.Cu" "F.Mask" "F.Paste")
			(net "ENET10G_2_MOD_DEF0")
		)
		(pad "2" smd rect
			(at -0.40005 0 180)
			(size 0.4572 0.508)
			(layers "F.Cu" "F.Mask" "F.Paste")
			(net "SFP2_PRESENT_N")
		)
	)
)
